# T6G (Grand Teton) — schematic netlist excerpt (pin names and nets, part order shuffled) for the footprints in the layout excerpt that follows; sources: Cadence DE-HDL packaged netlist, KiCad conversion of 04192023_DAF0TMB3IC0_F0TG_MB_C_brd_V02_OCP.brd

PC617  Q_CAP  2.2UF 10V 10% X6S  pkg C0402  page 223 : A = PVDDIO_P1_VCC3 ; B = GND
R6160  Q_RES  1K 1% CHIP  pkg 0402LF  page 112 : A = PD_P2E_BUF2_ENSMB ; B = GND

(kicad_pcb
	(version 20260206)
	(generator "pcbnew")
	(generator_version "10.0")
	(general
		(thickness 1.6)
		(legacy_teardrops no)
	)
	(paper "A4")
	(title_block
		(title "04192023_DAF0TMB3IC0_F0TG_MB_C_brd_V02_OCP.brd")
		(comment 1 "Grand Teton / footprints 4607-4608 of 8354")
	)
	(layers
		(0 "F.Cu" signal "TOP")
		(4 "In1.Cu" signal "GND")
		(6 "In2.Cu" signal "IN1")
		(8 "In3.Cu" signal "GND1")
		(10 "In4.Cu" signal "IN2")
		(12 "In5.Cu" signal "GND2")
		(14 "In6.Cu" signal "IN3")
		(16 "In7.Cu" signal "GND3")
		(18 "In8.Cu" signal "VCC")
		(20 "In9.Cu" signal "VCC1")
		(22 "In10.Cu" signal "GND4")
		(24 "In11.Cu" signal "IN4")
		(26 "In12.Cu" signal "GND5")
		(28 "In13.Cu" signal "IN5")
		(30 "In14.Cu" signal "GND6")
		(32 "In15.Cu" signal "IN6")
		(34 "In16.Cu" signal "GND7")
		(2 "B.Cu" signal "BOTTOM")
		(9 "F.Adhes" user "F.Adhesive")
		(11 "B.Adhes" user "B.Adhesive")
		(13 "F.Paste" user "Package Geometry/Pastemask Top")
		(15 "B.Paste" user "Package Geometry/Pastemask Bottom")
		(5 "F.SilkS" user "Ref Des/Silkscreen Top")
		(7 "B.SilkS" user "Ref Des/Silkscreen Bottom")
		(1 "F.Mask" user "Board Geometry/Soldermask Top")
		(3 "B.Mask" user "Board Geometry/Soldermask Bottom")
		(17 "Dwgs.User" user "User.Drawings")
		(19 "Cmts.User" user "User.Comments")
		(21 "Eco1.User" user "User.Eco1")
		(23 "Eco2.User" user "User.Eco2")
		(25 "Edge.Cuts" user "Board Geometry/Outline")
		(27 "Margin" user)
		(31 "F.CrtYd" user "Package Geometry/Place Bound Top")
		(29 "B.CrtYd" user "Package Geometry/Place Bound Bottom")
		(35 "F.Fab" user "Ref Des/Assembly Top")
		(33 "B.Fab" user "Ref Des/Assembly Bottom")
	)
	(footprint ""
		(layer "F.Cu")
		(at 33.198054 -349.386398 90)
		(property "Reference" "PC617"
			(at 0 0 90)
			(layer "F.SilkS")
			(hide yes)
			(effects
				(font
					(size 1.27 1.27)
				)
			)
		)
		(property "Value" ""
			(at 0 0 90)
			(layer "F.Fab")
			(effects
				(font
					(size 1.27 1.27)
				)
			)
		)
		(duplicate_pad_numbers_are_jumpers no)
		(fp_line
			(start 0.7874 -0.4064)
			(end 0.7874 0.4064)
			(stroke
				(width 0.1524)
				(type default)
			)
			(layer "F.SilkS")
		)
		(fp_line
			(start -0.7874 -0.4064)
			(end 0.7874 -0.4064)
			(stroke
				(width 0.1524)
				(type default)
			)
			(layer "F.SilkS")
		)
		(fp_line
			(start 0.7874 0.4064)
			(end 0.447802 0.4064)
			(stroke
				(width 0.1524)
				(type default)
			)
			(layer "F.SilkS")
		)
		(fp_line
			(start -0.237998 0.4064)
			(end -0.7874 0.4064)
			(stroke
				(width 0.1524)
				(type default)
			)
			(layer "F.SilkS")
		)
		(fp_line
			(start -0.7874 0.4064)
			(end -0.7874 -0.4064)
			(stroke
				(width 0.1524)
				(type default)
			)
			(layer "F.SilkS")
		)
		(fp_line
			(start -0.12065 -0.305054)
			(end -0.12065 -0.2794)
			(stroke
				(width 0.1)
				(type default)
			)
			(layer "F.Fab")
		)
		(fp_line
			(start -0.67945 -0.305054)
			(end -0.12065 -0.305054)
			(stroke
				(width 0.1)
				(type default)
			)
			(layer "F.Fab")
		)
		(fp_line
			(start 0.67945 -0.3048)
			(end 0.67945 0.3048)
			(stroke
				(width 0.1)
				(type default)
			)
			(layer "F.Fab")
		)
		(fp_line
			(start 0.12065 -0.3048)
			(end 0.67945 -0.3048)
			(stroke
				(width 0.1)
				(type default)
			)
			(layer "F.Fab")
		)
		(fp_line
			(start 0.12065 -0.2794)
			(end 0.12065 -0.3048)
			(stroke
				(width 0.1)
				(type default)
			)
			(layer "F.Fab")
		)
		(fp_line
			(start -0.12065 -0.2794)
			(end 0.12065 -0.2794)
			(stroke
				(width 0.1)
				(type default)
			)
			(layer "F.Fab")
		)
		(fp_line
			(start 0.120396 0.2794)
			(end -0.12065 0.2794)
			(stroke
				(width 0.1)
				(type default)
			)
			(layer "F.Fab")
		)
		(fp_line
			(start -0.12065 0.2794)
			(end -0.12065 0.3048)
			(stroke
				(width 0.1)
				(type default)
			)
			(layer "F.Fab")
		)
		(fp_line
			(start 0.67945 0.3048)
			(end 0.120396 0.3048)
			(stroke
				(width 0.1)
				(type default)
			)
			(layer "F.Fab")
		)
		(fp_line
			(start 0.120396 0.3048)
			(end 0.120396 0.2794)
			(stroke
				(width 0.1)
				(type default)
			)
			(layer "F.Fab")
		)
		(fp_line
			(start -0.12065 0.3048)
			(end -0.67945 0.3048)
			(stroke
				(width 0.1)
				(type default)
			)
			(layer "F.Fab")
		)
		(fp_line
			(start -0.67945 0.3048)
			(end -0.67945 -0.305054)
			(stroke
				(width 0.1)
				(type default)
			)
			(layer "F.Fab")
		)
		(pad "1" smd circle
			(at -0.40005 0 90)
			(size 0 0)
			(layers "F.Cu" "F.Mask" "F.Paste")
			(net "PVDDIO_P1_VCC3")
		)
		(pad "2" smd circle
			(at 0.40005 0 90)
			(size 0 0)
			(layers "F.Cu" "F.Mask" "F.Paste")
			(net "GND")
		)
	)
	(footprint ""
		(layer "F.Cu")
		(at 18.828258 -427.580298 90)
		(property "Reference" "R6160"
			(at 0 0 90)
			(layer "F.SilkS")
			(hide yes)
			(effects
				(font
					(size 1.27 1.27)
				)
			)
		)
		(property "Value" ""
			(at 0 0 90)
			(layer "F.Fab")
			(effects
				(font
					(size 1.27 1.27)
				)
			)
		)
		(duplicate_pad_numbers_are_jumpers no)
		(fp_line
			(start 0.7874 -0.4064)
			(end 0.7874 0.4064)
			(stroke
				(width 0.1524)
				(type default)
			)
			(layer "F.SilkS")
		)
		(fp_line
			(start -0.7874 -0.4064)
			(end 0.7874 -0.4064)
			(stroke
				(width 0.1524)
				(type default)
			)
			(layer "F.SilkS")
		)
		(fp_line
			(start 0.7874 0.4064)
			(end -0.7874 0.4064)
			(stroke
				(width 0.1524)
				(type default)
			)
			(layer "F.SilkS")
		)
		(fp_line
			(start -0.7874 0.4064)
			(end -0.7874 -0.4064)
			(stroke
				(width 0.1524)
				(type default)
			)
			(layer "F.SilkS")
		)
		(fp_line
			(start -0.12065 -0.305054)
			(end -0.12065 -0.2794)
			(stroke
				(width 0.1)
				(type default)
			)
			(layer "F.Fab")
		)
		(fp_line
			(start -0.67945 -0.305054)
			(end -0.12065 -0.305054)
			(stroke
				(width 0.1)
				(type default)
			)
			(layer "F.Fab")
		)
		(fp_line
			(start 0.67945 -0.3048)
			(end 0.67945 0.3048)
			(stroke
				(width 0.1)
				(type default)
			)
			(layer "F.Fab")
		)
		(fp_line
			(start 0.12065 -0.3048)
			(end 0.67945 -0.3048)
			(stroke
				(width 0.1)
				(type default)
			)
			(layer "F.Fab")
		)
		(fp_line
			(start 0.12065 -0.2794)
			(end 0.12065 -0.3048)
			(stroke
				(width 0.1)
				(type default)
			)
			(layer "F.Fab")
		)
		(fp_line
			(start -0.12065 -0.2794)
			(end 0.12065 -0.2794)
			(stroke
				(width 0.1)
				(type default)
			)
			(layer "F.Fab")
		)
		(fp_line
			(start 0.120396 0.2794)
			(end -0.12065 0.2794)
			(stroke
				(width 0.1)
				(type default)
			)
			(layer "F.Fab")
		)
		(fp_line
			(start -0.12065 0.2794)
			(end -0.12065 0.3048)
			(stroke
				(width 0.1)
				(type default)
			)
			(layer "F.Fab")
		)
		(fp_line
			(start 0.67945 0.3048)
			(end 0.120396 0.3048)
			(stroke
				(width 0.1)
				(type default)
			)
			(layer "F.Fab")
		)
		(fp_line
			(start 0.120396 0.3048)
			(end 0.120396 0.2794)
			(stroke
				(width 0.1)
				(type default)
			)
			(layer "F.Fab")
		)
		(fp_line
			(start -0.12065 0.3048)
			(end -0.67945 0.3048)
			(stroke
				(width 0.1)
				(type default)
			)
			(layer "F.Fab")
		)
		(fp_line
			(start -0.67945 0.3048)
			(end -0.67945 -0.305054)
			(stroke
				(width 0.1)
				(type default)
			)
			(layer "F.Fab")
		)
		(pad "1" smd circle
			(at -0.40005 0 90)
			(size 0 0)
			(layers "F.Cu" "F.Mask" "F.Paste")
			(net "PD_P2E_BUF2_ENSMB")
		)
		(pad "2" smd circle
			(at 0.40005 0 90)
			(size 0 0)
			(layers "F.Cu" "F.Mask" "F.Paste")
			(net "GND")
		)
	)
)
